(kicad_pcb
	(version 20260206)
	(generator "pcbnew")
	(generator_version "10.0")
	(general
		(thickness 1.6)
		(legacy_teardrops no)
	)
	(paper "A4")
	(title_block
		(title "pdpb — Lightning_PDPB_BRD.brd")
		(comment 1 "Lightning (Wiwynn / Facebook NVMe JBOF) / footprints 505-512 of 1140")
	)
	(layers
		(0 "F.Cu" signal "TOP")
		(4 "In1.Cu" signal "L2GND")
		(6 "In2.Cu" signal "L3")
		(8 "In3.Cu" signal "L4VCC")
		(10 "In4.Cu" signal "L5VCC")
		(12 "In5.Cu" signal "L6")
		(14 "In6.Cu" signal "L7GND")
		(2 "B.Cu" signal "BOTTOM")
		(9 "F.Adhes" user "F.Adhesive")
		(11 "B.Adhes" user "B.Adhesive")
		(13 "F.Paste" user "Package Geometry/Pastemask Top")
		(15 "B.Paste" user "Package Geometry/Pastemask Bottom")
		(5 "F.SilkS" user "Ref Des/Silkscreen Top")
		(7 "B.SilkS" user "Ref Des/Silkscreen Bottom")
		(1 "F.Mask" user "Board Geometry/Soldermask Top")
		(3 "B.Mask" user "Board Geometry/Soldermask Bottom")
		(17 "Dwgs.User" user "User.Drawings")
		(19 "Cmts.User" user "User.Comments")
		(21 "Eco1.User" user "User.Eco1")
		(23 "Eco2.User" user "User.Eco2")
		(25 "Edge.Cuts" user "Board Geometry/Outline")
		(27 "Margin" user)
		(31 "F.CrtYd" user "Package Geometry/Place Bound Top")
		(29 "B.CrtYd" user "Package Geometry/Place Bound Bottom")
		(35 "F.Fab" user "Ref Des/Assembly Top")
		(33 "B.Fab" user "Ref Des/Assembly Bottom")
	)
	(footprint ""
		(layer "F.Cu")
		(at 90.297 -92.964)
		(property "Reference" "R9127"
			(at 0 0 0)
			(layer "F.SilkS")
			(hide yes)
			(effects
				(font
					(size 1.27 1.27)
				)
			)
		)
		(property "Value" "27R2F-GP"
			(at 0.064008 -3.993896 0)
			(unlocked yes)
			(layer "F.Fab")
			(hide yes)
			(effects
				(font
					(size 1.016 1.016)
					(thickness 0.1524)
				)
			)
		)
		(property "Device Type" "R402H16"
			(at 0.064008 -5.517896 0)
			(unlocked yes)
			(layer "F.Fab")
			(hide yes)
			(effects
				(font
					(size 1.016 1.016)
					(thickness 0.1524)
				)
			)
		)
		(duplicate_pad_numbers_are_jumpers no)
		(fp_line
			(start -0.508 -0.9398)
			(end -0.508 0.9398)
			(stroke
				(width 0.1524)
				(type default)
			)
			(layer "F.SilkS")
		)
		(fp_line
			(start 0.508 -0.9398)
			(end -0.508 -0.9398)
			(stroke
				(width 0.1524)
				(type default)
			)
			(layer "F.SilkS")
		)
		(fp_rect
			(start -0.508 0.9398)
			(end 0.508 -0.9398)
			(stroke
				(width 0)
				(type default)
			)
			(fill no)
			(layer "F.CrtYd")
		)
		(fp_rect
			(start -0.508 0.9398)
			(end 0.508 -0.9398)
			(stroke
				(width 0)
				(type default)
			)
			(fill no)
			(layer "F.Fab")
		)
		(pad "1" smd custom
			(at 0 -0.4445)
			(size 0.1397 0.1397)
			(layers "F.Cu" "F.Mask" "F.Paste")
			(net "PE_CLK_100M_DR9_1_R_P")
			(options
				(clearance outline)
				(anchor circle)
			)
			(primitives
				(gr_poly
					(pts
						(arc
							(start -0.1778 -0.2794)
							(mid -0.249642 -0.249642)
							(end -0.2794 -0.1778)
						)
						(arc
							(start -0.2794 0.1778)
							(mid -0.249642 0.249642)
							(end -0.1778 0.2794)
						)
						(arc
							(start 0.1778 0.2794)
							(mid 0.249642 0.249642)
							(end 0.2794 0.1778)
						)
						(arc
							(start 0.2794 -0.1778)
							(mid 0.249642 -0.249642)
							(end 0.1778 -0.2794)
						)
					)
					(width 0)
					(fill yes)
				)
			)
		)
		(pad "2" smd custom
			(at 0 0.4445)
			(size 0.1397 0.1397)
			(layers "F.Cu" "F.Mask" "F.Paste")
			(net "PE_CLK100M_DR9_1_P")
			(options
				(clearance outline)
				(anchor circle)
			)
			(primitives
				(gr_poly
					(pts
						(arc
							(start -0.1778 -0.2794)
							(mid -0.249642 -0.249642)
							(end -0.2794 -0.1778)
						)
						(arc
							(start -0.2794 0.1778)
							(mid -0.249642 0.249642)
							(end -0.1778 0.2794)
						)
						(arc
							(start 0.1778 0.2794)
							(mid 0.249642 0.249642)
							(end 0.2794 0.1778)
						)
						(arc
							(start 0.2794 -0.1778)
							(mid 0.249642 -0.249642)
							(end 0.1778 -0.2794)
						)
					)
					(width 0)
					(fill yes)
				)
			)
		)
	)
	(footprint ""
		(layer "F.Cu")
		(at 101.092 -103.759)
		(property "Reference" "R9510"
			(at 0 0 0)
			(layer "F.SilkS")
			(hide yes)
			(effects
				(font
					(size 1.27 1.27)
				)
			)
		)
		(property "Value" "4K7R2F-GP"
			(at 0.064008 -3.993896 0)
			(unlocked yes)
			(layer "F.Fab")
			(hide yes)
			(effects
				(font
					(size 1.016 1.016)
					(thickness 0.1524)
				)
			)
		)
		(property "Device Type" "R402H16"
			(at 0.064008 -5.517896 0)
			(unlocked yes)
			(layer "F.Fab")
			(hide yes)
			(effects
				(font
					(size 1.016 1.016)
					(thickness 0.1524)
				)
			)
		)
		(duplicate_pad_numbers_are_jumpers no)
		(fp_line
			(start -0.508 -0.9398)
			(end -0.508 0.9398)
			(stroke
				(width 0.1524)
				(type default)
			)
			(layer "F.SilkS")
		)
		(fp_line
			(start 0.508 -0.9398)
			(end -0.508 -0.9398)
			(stroke
				(width 0.1524)
				(type default)
			)
			(layer "F.SilkS")
		)
		(fp_rect
			(start -0.508 0.9398)
			(end 0.508 -0.9398)
			(stroke
				(width 0)
				(type default)
			)
			(fill no)
			(layer "F.CrtYd")
		)
		(fp_rect
			(start -0.508 0.9398)
			(end 0.508 -0.9398)
			(stroke
				(width 0)
				(type default)
			)
			(fill no)
			(layer "F.Fab")
		)
		(pad "1" smd custom
			(at 0 -0.4445)
			(size 0.1397 0.1397)
			(layers "F.Cu" "F.Mask" "F.Paste")
			(net "P3V3")
			(options
				(clearance outline)
				(anchor circle)
			)
			(primitives
				(gr_poly
					(pts
						(arc
							(start -0.1778 -0.2794)
							(mid -0.249642 -0.249642)
							(end -0.2794 -0.1778)
						)
						(arc
							(start -0.2794 0.1778)
							(mid -0.249642 0.249642)
							(end -0.1778 0.2794)
						)
						(arc
							(start 0.1778 0.2794)
							(mid 0.249642 0.249642)
							(end 0.2794 0.1778)
						)
						(arc
							(start 0.2794 -0.1778)
							(mid 0.249642 -0.249642)
							(end 0.1778 -0.2794)
						)
					)
					(width 0)
					(fill yes)
				)
			)
		)
		(pad "2" smd custom
			(at 0 0.4445)
			(size 0.1397 0.1397)
			(layers "F.Cu" "F.Mask" "F.Paste")
			(net "CLK_BUFFER_EU4_VOE_N")
			(options
				(clearance outline)
				(anchor circle)
			)
			(primitives
				(gr_poly
					(pts
						(arc
							(start -0.1778 -0.2794)
							(mid -0.249642 -0.249642)
							(end -0.2794 -0.1778)
						)
						(arc
							(start -0.2794 0.1778)
							(mid -0.249642 0.249642)
							(end -0.1778 0.2794)
						)
						(arc
							(start 0.1778 0.2794)
							(mid 0.249642 0.249642)
							(end 0.2794 0.1778)
						)
						(arc
							(start 0.2794 -0.1778)
							(mid 0.249642 -0.249642)
							(end 0.1778 -0.2794)
						)
					)
					(width 0)
					(fill yes)
				)
			)
		)
	)
	(footprint ""
		(layer "F.Cu")
		(at 82.931 -436.118 90)
		(property "Reference" "SR947"
			(at 0 0 90)
			(layer "F.SilkS")
			(hide yes)
			(effects
				(font
					(size 1.27 1.27)
				)
			)
		)
		(property "Value" "4K7R2F-GP"
			(at 0.064008 -3.993896 90)
			(unlocked yes)
			(layer "F.Fab")
			(hide yes)
			(effects
				(font
					(size 1.016 1.016)
					(thickness 0.1524)
				)
			)
		)
		(property "Device Type" "R402H16"
			(at 0.064008 -5.517896 90)
			(unlocked yes)
			(layer "F.Fab")
			(hide yes)
			(effects
				(font
					(size 1.016 1.016)
					(thickness 0.1524)
				)
			)
		)
		(duplicate_pad_numbers_are_jumpers no)
		(fp_line
			(start 0.508 -0.9398)
			(end -0.508 -0.9398)
			(stroke
				(width 0.1524)
				(type default)
			)
			(layer "F.SilkS")
		)
		(fp_line
			(start -0.508 -0.9398)
			(end -0.508 0.9398)
			(stroke
				(width 0.1524)
				(type default)
			)
			(layer "F.SilkS")
		)
		(fp_rect
			(start -0.508 0.9398)
			(end 0.508 -0.9398)
			(stroke
				(width 0)
				(type default)
			)
			(fill no)
			(layer "F.CrtYd")
		)
		(fp_rect
			(start -0.508 0.9398)
			(end 0.508 -0.9398)
			(stroke
				(width 0)
				(type default)
			)
			(fill no)
			(layer "F.Fab")
		)
		(pad "1" smd custom
			(at 0 -0.4445 90)
			(size 0.1397 0.1397)
			(layers "F.Cu" "F.Mask" "F.Paste")
			(net "VDD_DIFF_1")
			(options
				(clearance outline)
				(anchor circle)
			)
			(primitives
				(gr_poly
					(pts
						(arc
							(start -0.1778 -0.2794)
							(mid -0.249642 -0.249642)
							(end -0.2794 -0.1778)
						)
						(arc
							(start -0.2794 0.1778)
							(mid -0.249642 0.249642)
							(end -0.1778 0.2794)
						)
						(arc
							(start 0.1778 0.2794)
							(mid 0.249642 0.249642)
							(end 0.2794 0.1778)
						)
						(arc
							(start 0.2794 -0.1778)
							(mid 0.249642 -0.249642)
							(end 0.1778 -0.2794)
						)
					)
					(width 0)
					(fill yes)
				)
			)
		)
		(pad "2" smd custom
			(at 0 0.4445 90)
			(size 0.1397 0.1397)
			(layers "F.Cu" "F.Mask" "F.Paste")
			(net "CLK_BUF_EU1_HIBW_BYPM_LOBW#")
			(options
				(clearance outline)
				(anchor circle)
			)
			(primitives
				(gr_poly
					(pts
						(arc
							(start -0.1778 -0.2794)
							(mid -0.249642 -0.249642)
							(end -0.2794 -0.1778)
						)
						(arc
							(start -0.2794 0.1778)
							(mid -0.249642 0.249642)
							(end -0.1778 0.2794)
						)
						(arc
							(start 0.1778 0.2794)
							(mid 0.249642 0.249642)
							(end 0.2794 0.1778)
						)
						(arc
							(start 0.2794 -0.1778)
							(mid 0.249642 -0.249642)
							(end 0.1778 -0.2794)
						)
					)
					(width 0)
					(fill yes)
				)
			)
		)
	)
	(footprint ""
		(layer "F.Cu")
		(at 205.867 -46.482)
		(property "Reference" "TP6"
			(at 0 0 0)
			(layer "F.SilkS")
			(hide yes)
			(effects
				(font
					(size 1.27 1.27)
				)
			)
		)
		(property "Value" "TPAD32-GP"
			(at -0.0508 -1.6764 0)
			(unlocked yes)
			(layer "F.Fab")
			(hide yes)
			(effects
				(font
					(size 1.016 1.016)
					(thickness 0.1524)
				)
			)
		)
		(property "Device Type" "TPAD32"
			(at -0.0508 -3.2004 0)
			(unlocked yes)
			(layer "F.Fab")
			(hide yes)
			(effects
				(font
					(size 1.016 1.016)
					(thickness 0.1524)
				)
			)
		)
		(duplicate_pad_numbers_are_jumpers no)
		(fp_poly
			(pts
				(arc
					(start 0.4064 0)
					(mid -0.4064 0)
					(end 0.4064 0)
				)
			)
			(stroke
				(width 0)
				(type default)
			)
			(fill no)
			(layer "F.CrtYd")
		)
		(fp_poly
			(pts
				(arc
					(start 0.7112 0)
					(mid -0.7112 0)
					(end 0.7112 0)
				)
			)
			(stroke
				(width 0)
				(type default)
			)
			(fill no)
			(layer "F.Fab")
		)
		(pad "1" smd circle
			(at 0 0)
			(size 0.8128 0.8128)
			(layers "F.Cu" "F.Mask" "F.Paste")
			(net "I2C_B_TMP3_ALERT")
		)
	)
	(footprint ""
		(layer "F.Cu")
		(at 75.184 -154.178)
		(property "Reference" "SR975"
			(at 0 0 0)
			(layer "F.SilkS")
			(hide yes)
			(effects
				(font
					(size 1.27 1.27)
				)
			)
		)
		(property "Value" "2KR2F-3-GP"
			(at 0.064008 -3.993896 0)
			(unlocked yes)
			(layer "F.Fab")
			(hide yes)
			(effects
				(font
					(size 1.016 1.016)
					(thickness 0.1524)
				)
			)
		)
		(property "Device Type" "R402H16"
			(at 0.064008 -5.517896 0)
			(unlocked yes)
			(layer "F.Fab")
			(hide yes)
			(effects
				(font
					(size 1.016 1.016)
					(thickness 0.1524)
				)
			)
		)
		(duplicate_pad_numbers_are_jumpers no)
		(fp_line
			(start -0.508 -0.9398)
			(end -0.508 0.9398)
			(stroke
				(width 0.1524)
				(type default)
			)
			(layer "F.SilkS")
		)
		(fp_line
			(start 0.508 -0.9398)
			(end -0.508 -0.9398)
			(stroke
				(width 0.1524)
				(type default)
			)
			(layer "F.SilkS")
		)
		(fp_rect
			(start -0.508 0.9398)
			(end 0.508 -0.9398)
			(stroke
				(width 0)
				(type default)
			)
			(fill no)
			(layer "F.CrtYd")
		)
		(fp_rect
			(start -0.508 0.9398)
			(end 0.508 -0.9398)
			(stroke
				(width 0)
				(type default)
			)
			(fill no)
			(layer "F.Fab")
		)
		(pad "1" smd custom
			(at 0 -0.4445)
			(size 0.1397 0.1397)
			(layers "F.Cu" "F.Mask" "F.Paste")
			(net "P3V3")
			(options
				(clearance outline)
				(anchor circle)
			)
			(primitives
				(gr_poly
					(pts
						(arc
							(start -0.1778 -0.2794)
							(mid -0.249642 -0.249642)
							(end -0.2794 -0.1778)
						)
						(arc
							(start -0.2794 0.1778)
							(mid -0.249642 0.249642)
							(end -0.1778 0.2794)
						)
						(arc
							(start 0.1778 0.2794)
							(mid 0.249642 0.249642)
							(end 0.2794 0.1778)
						)
						(arc
							(start 0.2794 -0.1778)
							(mid 0.249642 -0.249642)
							(end 0.1778 -0.2794)
						)
					)
					(width 0)
					(fill yes)
				)
			)
		)
		(pad "2" smd custom
			(at 0 0.4445)
			(size 0.1397 0.1397)
			(layers "F.Cu" "F.Mask" "F.Paste")
			(net "SCL_DR4")
			(options
				(clearance outline)
				(anchor circle)
			)
			(primitives
				(gr_poly
					(pts
						(arc
							(start -0.1778 -0.2794)
							(mid -0.249642 -0.249642)
							(end -0.2794 -0.1778)
						)
						(arc
							(start -0.2794 0.1778)
							(mid -0.249642 0.249642)
							(end -0.1778 0.2794)
						)
						(arc
							(start 0.1778 0.2794)
							(mid 0.249642 0.249642)
							(end 0.2794 0.1778)
						)
						(arc
							(start 0.2794 -0.1778)
							(mid 0.249642 -0.249642)
							(end 0.1778 -0.2794)
						)
					)
					(width 0)
					(fill yes)
				)
			)
		)
	)
	(footprint ""
		(layer "F.Cu")
		(at 30.861 -318.4652)
		(property "Reference" "SR1114"
			(at 0 0 0)
			(layer "F.SilkS")
			(hide yes)
			(effects
				(font
					(size 1.27 1.27)
				)
			)
		)
		(property "Value" "4K7R2F-GP"
			(at 0.064008 -3.993896 0)
			(unlocked yes)
			(layer "F.Fab")
			(hide yes)
			(effects
				(font
					(size 1.016 1.016)
					(thickness 0.1524)
				)
			)
		)
		(property "Device Type" "R402H16"
			(at 0.064008 -5.517896 0)
			(unlocked yes)
			(layer "F.Fab")
			(hide yes)
			(effects
				(font
					(size 1.016 1.016)
					(thickness 0.1524)
				)
			)
		)
		(duplicate_pad_numbers_are_jumpers no)
		(fp_line
			(start -0.508 -0.9398)
			(end -0.508 0.9398)
			(stroke
				(width 0.1524)
				(type default)
			)
			(layer "F.SilkS")
		)
		(fp_line
			(start 0.508 -0.9398)
			(end -0.508 -0.9398)
			(stroke
				(width 0.1524)
				(type default)
			)
			(layer "F.SilkS")
		)
		(fp_rect
			(start -0.508 0.9398)
			(end 0.508 -0.9398)
			(stroke
				(width 0)
				(type default)
			)
			(fill no)
			(layer "F.CrtYd")
		)
		(fp_rect
			(start -0.508 0.9398)
			(end 0.508 -0.9398)
			(stroke
				(width 0)
				(type default)
			)
			(fill no)
			(layer "F.Fab")
		)
		(pad "1" smd custom
			(at 0 -0.4445)
			(size 0.1397 0.1397)
			(layers "F.Cu" "F.Mask" "F.Paste")
			(net "DUALPORTEN#11")
			(options
				(clearance outline)
				(anchor circle)
			)
			(primitives
				(gr_poly
					(pts
						(arc
							(start -0.1778 -0.2794)
							(mid -0.249642 -0.249642)
							(end -0.2794 -0.1778)
						)
						(arc
							(start -0.2794 0.1778)
							(mid -0.249642 0.249642)
							(end -0.1778 0.2794)
						)
						(arc
							(start 0.1778 0.2794)
							(mid 0.249642 0.249642)
							(end 0.2794 0.1778)
						)
						(arc
							(start 0.2794 -0.1778)
							(mid 0.249642 -0.249642)
							(end 0.1778 -0.2794)
						)
					)
					(width 0)
					(fill yes)
				)
			)
		)
		(pad "2" smd custom
			(at 0 0.4445)
			(size 0.1397 0.1397)
			(layers "F.Cu" "F.Mask" "F.Paste")
			(net "GND")
			(options
				(clearance outline)
				(anchor circle)
			)
			(primitives
				(gr_poly
					(pts
						(arc
							(start -0.1778 -0.2794)
							(mid -0.249642 -0.249642)
							(end -0.2794 -0.1778)
						)
						(arc
							(start -0.2794 0.1778)
							(mid -0.249642 0.249642)
							(end -0.1778 0.2794)
						)
						(arc
							(start 0.1778 0.2794)
							(mid 0.249642 0.249642)
							(end 0.2794 0.1778)
						)
						(arc
							(start 0.2794 -0.1778)
							(mid 0.249642 -0.249642)
							(end 0.1778 -0.2794)
						)
					)
					(width 0)
					(fill yes)
				)
			)
		)
	)
	(footprint ""
		(layer "F.Cu")
		(at 79.502 -143.256)
		(property "Reference" "SR1046"
			(at 0 0 0)
			(layer "F.SilkS")
			(hide yes)
			(effects
				(font
					(size 1.27 1.27)
				)
			)
		)
		(property "Value" "4K7R2F-GP"
			(at 0.064008 -3.993896 0)
			(unlocked yes)
			(layer "F.Fab")
			(hide yes)
			(effects
				(font
					(size 1.016 1.016)
					(thickness 0.1524)
				)
			)
		)
		(property "Device Type" "R402H16"
			(at 0.064008 -5.517896 0)
			(unlocked yes)
			(layer "F.Fab")
			(hide yes)
			(effects
				(font
					(size 1.016 1.016)
					(thickness 0.1524)
				)
			)
		)
		(duplicate_pad_numbers_are_jumpers no)
		(fp_line
			(start -0.508 -0.9398)
			(end -0.508 0.9398)
			(stroke
				(width 0.1524)
				(type default)
			)
			(layer "F.SilkS")
		)
		(fp_line
			(start 0.508 -0.9398)
			(end -0.508 -0.9398)
			(stroke
				(width 0.1524)
				(type default)
			)
			(layer "F.SilkS")
		)
		(fp_rect
			(start -0.508 0.9398)
			(end 0.508 -0.9398)
			(stroke
				(width 0)
				(type default)
			)
			(fill no)
			(layer "F.CrtYd")
		)
		(fp_rect
			(start -0.508 0.9398)
			(end 0.508 -0.9398)
			(stroke
				(width 0)
				(type default)
			)
			(fill no)
			(layer "F.Fab")
		)
		(pad "1" smd custom
			(at 0 -0.4445)
			(size 0.1397 0.1397)
			(layers "F.Cu" "F.Mask" "F.Paste")
			(net "I2C_SW_EU16_ADDRESS_A2")
			(options
				(clearance outline)
				(anchor circle)
			)
			(primitives
				(gr_poly
					(pts
						(arc
							(start -0.1778 -0.2794)
							(mid -0.249642 -0.249642)
							(end -0.2794 -0.1778)
						)
						(arc
							(start -0.2794 0.1778)
							(mid -0.249642 0.249642)
							(end -0.1778 0.2794)
						)
						(arc
							(start 0.1778 0.2794)
							(mid 0.249642 0.249642)
							(end 0.2794 0.1778)
						)
						(arc
							(start 0.2794 -0.1778)
							(mid 0.249642 -0.249642)
							(end 0.1778 -0.2794)
						)
					)
					(width 0)
					(fill yes)
				)
			)
		)
		(pad "2" smd custom
			(at 0 0.4445)
			(size 0.1397 0.1397)
			(layers "F.Cu" "F.Mask" "F.Paste")
			(net "GND")
			(options
				(clearance outline)
				(anchor circle)
			)
			(primitives
				(gr_poly
					(pts
						(arc
							(start -0.1778 -0.2794)
							(mid -0.249642 -0.249642)
							(end -0.2794 -0.1778)
						)
						(arc
							(start -0.2794 0.1778)
							(mid -0.249642 0.249642)
							(end -0.1778 0.2794)
						)
						(arc
							(start 0.1778 0.2794)
							(mid 0.249642 0.249642)
							(end 0.2794 0.1778)
						)
						(arc
							(start 0.2794 -0.1778)
							(mid 0.249642 -0.249642)
							(end 0.1778 -0.2794)
						)
					)
					(width 0)
					(fill yes)
				)
			)
		)
	)
	(footprint ""
		(layer "F.Cu")
		(at 36.576 -62.103 180)
		(property "Reference" "PC1199"
			(at 0 0 180)
			(layer "F.SilkS")
			(hide yes)
			(effects
				(font
					(size 1.27 1.27)
				)
			)
		)
		(property "Value" "SCD1U25V3KX-GP"
			(at 0 -2.8194 180)
			(unlocked yes)
			(layer "F.Fab")
			(hide yes)
			(effects
				(font
					(size 1.016 1.016)
					(thickness 0.1524)
				)
			)
		)
		(property "Device Type" "C603H36"
			(at 0 -4.3434 180)
			(unlocked yes)
			(layer "F.Fab")
			(hide yes)
			(effects
				(font
					(size 1.016 1.016)
					(thickness 0.1524)
				)
			)
		)
		(duplicate_pad_numbers_are_jumpers no)
		(fp_line
			(start 0.508 0)
			(end -0.508 0)
			(stroke
				(width 0.2032)
				(type default)
			)
			(layer "F.SilkS")
		)
		(fp_rect
			(start -0.5842 1.3335)
			(end 0.5842 -1.3335)
			(stroke
				(width 0)
				(type default)
			)
			(fill no)
			(layer "F.CrtYd")
		)
		(fp_rect
			(start -0.5842 1.3335)
			(end 0.5842 -1.3335)
			(stroke
				(width 0)
				(type default)
			)
			(fill no)
			(layer "F.Fab")
		)
		(pad "1" smd custom
			(at 0 -0.762 180)
			(size 0.2159 0.2159)
			(layers "F.Cu" "F.Mask" "F.Paste")
			(net "P3V3")
			(options
				(clearance outline)
				(anchor circle)
			)
			(primitives
				(gr_poly
					(pts
						(arc
							(start -0.3302 -0.4318)
							(mid -0.402042 -0.402042)
							(end -0.4318 -0.3302)
						)
						(arc
							(start -0.4318 0.3302)
							(mid -0.402042 0.402042)
							(end -0.3302 0.4318)
						)
						(arc
							(start 0.3302 0.4318)
							(mid 0.402042 0.402042)
							(end 0.4318 0.3302)
						)
						(arc
							(start 0.4318 -0.3302)
							(mid 0.402042 -0.402042)
							(end 0.3302 -0.4318)
						)
					)
					(width 0)
					(fill yes)
				)
			)
		)
		(pad "2" smd custom
			(at 0 0.762 180)
			(size 0.2159 0.2159)
			(layers "F.Cu" "F.Mask" "F.Paste")
			(net "GND")
			(options
				(clearance outline)
				(anchor circle)
			)
			(primitives
				(gr_poly
					(pts
						(arc
							(start -0.3302 -0.4318)
							(mid -0.402042 -0.402042)
							(end -0.4318 -0.3302)
						)
						(arc
							(start -0.4318 0.3302)
							(mid -0.402042 0.402042)
							(end -0.3302 0.4318)
						)
						(arc
							(start 0.3302 0.4318)
							(mid 0.402042 0.402042)
							(end 0.4318 0.3302)
						)
						(arc
							(start 0.4318 -0.3302)
							(mid 0.402042 -0.402042)
							(end 0.3302 -0.4318)
						)
					)
					(width 0)
					(fill yes)
				)
			)
		)
	)
)
